# T6G (Grand Teton) — schematic netlist excerpt (pin names and nets, part order shuffled) for the footprints in the layout excerpt that follows; sources: Cadence DE-HDL packaged netlist, KiCad conversion of 04192023_DAF0TMB3IC0_F0TG_MB_C_brd_V02_OCP.brd

R6102  Q_RES  0 5% CHIP  pkg 0402LF  page 171 : A = SCM_JTAG_MUX_S0 ; B = SCM_JTAG_MUX_S0_R2
R1426  Q_RES  1K 1% EMPTY  pkg 0201LF  page 342 : A = P1V8_CPU1_RT_1D ; B = RXDET_BYP_RT_CPU1_P2
C3899  Q_CAP  22UF 4V 20% X6S  pkg C0402  page 68 : A = PVDDIO_P0 ; B = GND

(kicad_pcb
	(version 20260206)
	(generator "pcbnew")
	(generator_version "10.0")
	(general
		(thickness 1.6)
		(legacy_teardrops no)
	)
	(paper "A4")
	(title_block
		(title "04192023_DAF0TMB3IC0_F0TG_MB_C_brd_V02_OCP.brd")
		(comment 1 "Grand Teton / footprints 1913-1915 of 8354")
	)
	(layers
		(0 "F.Cu" signal "TOP")
		(4 "In1.Cu" signal "GND")
		(6 "In2.Cu" signal "IN1")
		(8 "In3.Cu" signal "GND1")
		(10 "In4.Cu" signal "IN2")
		(12 "In5.Cu" signal "GND2")
		(14 "In6.Cu" signal "IN3")
		(16 "In7.Cu" signal "GND3")
		(18 "In8.Cu" signal "VCC")
		(20 "In9.Cu" signal "VCC1")
		(22 "In10.Cu" signal "GND4")
		(24 "In11.Cu" signal "IN4")
		(26 "In12.Cu" signal "GND5")
		(28 "In13.Cu" signal "IN5")
		(30 "In14.Cu" signal "GND6")
		(32 "In15.Cu" signal "IN6")
		(34 "In16.Cu" signal "GND7")
		(2 "B.Cu" signal "BOTTOM")
		(9 "F.Adhes" user "F.Adhesive")
		(11 "B.Adhes" user "B.Adhesive")
		(13 "F.Paste" user "Package Geometry/Pastemask Top")
		(15 "B.Paste" user "Package Geometry/Pastemask Bottom")
		(5 "F.SilkS" user "Ref Des/Silkscreen Top")
		(7 "B.SilkS" user "Ref Des/Silkscreen Bottom")
		(1 "F.Mask" user "Board Geometry/Soldermask Top")
		(3 "B.Mask" user "Board Geometry/Soldermask Bottom")
		(17 "Dwgs.User" user "User.Drawings")
		(19 "Cmts.User" user "User.Comments")
		(21 "Eco1.User" user "User.Eco1")
		(23 "Eco2.User" user "User.Eco2")
		(25 "Edge.Cuts" user "Board Geometry/Outline")
		(27 "Margin" user)
		(31 "F.CrtYd" user "Package Geometry/Place Bound Top")
		(29 "B.CrtYd" user "Package Geometry/Place Bound Bottom")
		(35 "F.Fab" user "Ref Des/Assembly Top")
		(33 "B.Fab" user "Ref Des/Assembly Bottom")
	)
	(footprint ""
		(layer "F.Cu")
		(at 177.81016 -390.2075)
		(property "Reference" "R1426"
			(at 0 0 0)
			(layer "F.SilkS")
			(hide yes)
			(effects
				(font
					(size 1.27 1.27)
				)
			)
		)
		(property "Value" ""
			(at 0 0 0)
			(layer "F.Fab")
			(effects
				(font
					(size 1.27 1.27)
				)
			)
		)
		(duplicate_pad_numbers_are_jumpers no)
		(fp_line
			(start -0.32512 -0.175006)
			(end 0.32512 -0.175006)
			(stroke
				(width 0.1)
				(type default)
			)
			(layer "F.Fab")
		)
		(fp_line
			(start -0.32512 0.175006)
			(end -0.32512 -0.175006)
			(stroke
				(width 0.1)
				(type default)
			)
			(layer "F.Fab")
		)
		(fp_line
			(start 0.32512 -0.175006)
			(end 0.32512 0.175006)
			(stroke
				(width 0.1)
				(type default)
			)
			(layer "F.Fab")
		)
		(fp_line
			(start 0.32512 0.175006)
			(end -0.32512 0.175006)
			(stroke
				(width 0.1)
				(type default)
			)
			(layer "F.Fab")
		)
		(pad "1" smd rect
			(at -0.2667 0)
			(size 0.3048 0.381)
			(layers "F.Cu" "F.Mask" "F.Paste")
			(net "P1V8_CPU1_RT_1D")
		)
		(pad "2" smd rect
			(at 0.2667 0 180)
			(size 0.3048 0.381)
			(layers "F.Cu" "F.Mask" "F.Paste")
			(net "RXDET_BYP_RT_CPU1_P2")
		)
	)
	(footprint ""
		(layer "F.Cu")
		(at 356.29596 -258.795012)
		(property "Reference" "C3899"
			(at 0 0 0)
			(layer "F.SilkS")
			(hide yes)
			(effects
				(font
					(size 1.27 1.27)
				)
			)
		)
		(property "Value" ""
			(at 0 0 0)
			(layer "F.Fab")
			(effects
				(font
					(size 1.27 1.27)
				)
			)
		)
		(duplicate_pad_numbers_are_jumpers no)
		(fp_line
			(start -0.7874 -0.4064)
			(end 0.7874 -0.4064)
			(stroke
				(width 0.1524)
				(type default)
			)
			(layer "F.SilkS")
		)
		(fp_line
			(start -0.7874 0.4064)
			(end -0.7874 -0.4064)
			(stroke
				(width 0.1524)
				(type default)
			)
			(layer "F.SilkS")
		)
		(fp_line
			(start 0.7874 -0.4064)
			(end 0.7874 0.4064)
			(stroke
				(width 0.1524)
				(type default)
			)
			(layer "F.SilkS")
		)
		(fp_line
			(start 0.7874 0.4064)
			(end -0.7874 0.4064)
			(stroke
				(width 0.1524)
				(type default)
			)
			(layer "F.SilkS")
		)
		(fp_line
			(start -0.67945 -0.305054)
			(end -0.12065 -0.305054)
			(stroke
				(width 0.1)
				(type default)
			)
			(layer "F.Fab")
		)
		(fp_line
			(start -0.67945 0.3048)
			(end -0.67945 -0.305054)
			(stroke
				(width 0.1)
				(type default)
			)
			(layer "F.Fab")
		)
		(fp_line
			(start -0.12065 -0.305054)
			(end -0.12065 -0.2794)
			(stroke
				(width 0.1)
				(type default)
			)
			(layer "F.Fab")
		)
		(fp_line
			(start -0.12065 -0.2794)
			(end 0.12065 -0.2794)
			(stroke
				(width 0.1)
				(type default)
			)
			(layer "F.Fab")
		)
		(fp_line
			(start -0.12065 0.2794)
			(end -0.12065 0.3048)
			(stroke
				(width 0.1)
				(type default)
			)
			(layer "F.Fab")
		)
		(fp_line
			(start -0.12065 0.3048)
			(end -0.67945 0.3048)
			(stroke
				(width 0.1)
				(type default)
			)
			(layer "F.Fab")
		)
		(fp_line
			(start 0.120396 0.2794)
			(end -0.12065 0.2794)
			(stroke
				(width 0.1)
				(type default)
			)
			(layer "F.Fab")
		)
		(fp_line
			(start 0.120396 0.3048)
			(end 0.120396 0.2794)
			(stroke
				(width 0.1)
				(type default)
			)
			(layer "F.Fab")
		)
		(fp_line
			(start 0.12065 -0.3048)
			(end 0.67945 -0.3048)
			(stroke
				(width 0.1)
				(type default)
			)
			(layer "F.Fab")
		)
		(fp_line
			(start 0.12065 -0.2794)
			(end 0.12065 -0.3048)
			(stroke
				(width 0.1)
				(type default)
			)
			(layer "F.Fab")
		)
		(fp_line
			(start 0.67945 -0.3048)
			(end 0.67945 0.3048)
			(stroke
				(width 0.1)
				(type default)
			)
			(layer "F.Fab")
		)
		(fp_line
			(start 0.67945 0.3048)
			(end 0.120396 0.3048)
			(stroke
				(width 0.1)
				(type default)
			)
			(layer "F.Fab")
		)
		(pad "1" smd circle
			(at -0.40005 0)
			(size 0 0)
			(layers "F.Cu" "F.Mask" "F.Paste")
			(net "PVDDIO_P0")
		)
		(pad "2" smd circle
			(at 0.40005 0)
			(size 0 0)
			(layers "F.Cu" "F.Mask" "F.Paste")
			(net "GND")
		)
	)
	(footprint ""
		(layer "F.Cu")
		(at 138.426952 -57.516014 180)
		(property "Reference" "R6102"
			(at 0 0 180)
			(layer "F.SilkS")
			(hide yes)
			(effects
				(font
					(size 1.27 1.27)
				)
			)
		)
		(property "Value" ""
			(at 0 0 180)
			(layer "F.Fab")
			(effects
				(font
					(size 1.27 1.27)
				)
			)
		)
		(duplicate_pad_numbers_are_jumpers no)
		(fp_line
			(start 0.7874 0.4064)
			(end -0.7874 0.4064)
			(stroke
				(width 0.1524)
				(type default)
			)
			(layer "F.SilkS")
		)
		(fp_line
			(start 0.7874 -0.4064)
			(end 0.7874 0.4064)
			(stroke
				(width 0.1524)
				(type default)
			)
			(layer "F.SilkS")
		)
		(fp_line
			(start -0.7874 0.4064)
			(end -0.7874 -0.4064)
			(stroke
				(width 0.1524)
				(type default)
			)
			(layer "F.SilkS")
		)
		(fp_line
			(start -0.7874 -0.4064)
			(end 0.7874 -0.4064)
			(stroke
				(width 0.1524)
				(type default)
			)
			(layer "F.SilkS")
		)
		(fp_line
			(start 0.67945 0.3048)
			(end 0.120396 0.3048)
			(stroke
				(width 0.1)
				(type default)
			)
			(layer "F.Fab")
		)
		(fp_line
			(start 0.67945 -0.3048)
			(end 0.67945 0.3048)
			(stroke
				(width 0.1)
				(type default)
			)
			(layer "F.Fab")
		)
		(fp_line
			(start 0.12065 -0.2794)
			(end 0.12065 -0.3048)
			(stroke
				(width 0.1)
				(type default)
			)
			(layer "F.Fab")
		)
		(fp_line
			(start 0.12065 -0.3048)
			(end 0.67945 -0.3048)
			(stroke
				(width 0.1)
				(type default)
			)
			(layer "F.Fab")
		)
		(fp_line
			(start 0.120396 0.3048)
			(end 0.120396 0.2794)
			(stroke
				(width 0.1)
				(type default)
			)
			(layer "F.Fab")
		)
		(fp_line
			(start 0.120396 0.2794)
			(end -0.12065 0.2794)
			(stroke
				(width 0.1)
				(type default)
			)
			(layer "F.Fab")
		)
		(fp_line
			(start -0.12065 0.3048)
			(end -0.67945 0.3048)
			(stroke
				(width 0.1)
				(type default)
			)
			(layer "F.Fab")
		)
		(fp_line
			(start -0.12065 0.2794)
			(end -0.12065 0.3048)
			(stroke
				(width 0.1)
				(type default)
			)
			(layer "F.Fab")
		)
		(fp_line
			(start -0.12065 -0.2794)
			(end 0.12065 -0.2794)
			(stroke
				(width 0.1)
				(type default)
			)
			(layer "F.Fab")
		)
		(fp_line
			(start -0.12065 -0.305054)
			(end -0.12065 -0.2794)
			(stroke
				(width 0.1)
				(type default)
			)
			(layer "F.Fab")
		)
		(fp_line
			(start -0.67945 0.3048)
			(end -0.67945 -0.305054)
			(stroke
				(width 0.1)
				(type default)
			)
			(layer "F.Fab")
		)
		(fp_line
			(start -0.67945 -0.305054)
			(end -0.12065 -0.305054)
			(stroke
				(width 0.1)
				(type default)
			)
			(layer "F.Fab")
		)
		(pad "1" smd circle
			(at -0.40005 0 180)
			(size 0 0)
			(layers "F.Cu" "F.Mask" "F.Paste")
			(net "SCM_JTAG_MUX_S0")
		)
		(pad "2" smd circle
			(at 0.40005 0 180)
			(size 0 0)
			(layers "F.Cu" "F.Mask" "F.Paste")
			(net "SCM_JTAG_MUX_S0_R2")
		)
	)
)
